# S9S_MB_2U (Grand Teton) — schematic netlist excerpt (pin names and nets, part order shuffled) for the footprints in the layout excerpt that follows; sources: Cadence DE-HDL packaged netlist, KiCad conversion of 03242023_DA0F0TMBIJ0_F0T_Motherboard_J_brd_V01_OCP.brd

C352  Q_CAP  47UF 4V 20% X6S  pkg C0805  page 79 : A = PVCCIN_CPU1 ; B = GND
R1394  Q_RES  240 1% EMPTY  pkg 0402LF  page 120 : A = GND ; B = FM_S3M_CPU1_LVC1_GPIO_3
PR1333  Q_RES  0 5% CHIP  pkg 0402LF  page 290 : A = PVCCFA_EHV_FIVRA_CPU1_VOS3 ; B = PVCCFA_EHV_FIVRA_CPU1

(kicad_pcb
	(version 20260206)
	(generator "pcbnew")
	(generator_version "10.0")
	(general
		(thickness 1.6)
		(legacy_teardrops no)
	)
	(paper "A4")
	(title_block
		(title "03242023_DA0F0TMBIJ0_F0T_Motherboard_J_brd_V01_OCP.brd")
		(comment 1 "Grand Teton / footprints 5078-5080 of 6105")
	)
	(layers
		(0 "F.Cu" signal "TOP")
		(4 "In1.Cu" signal "GND")
		(6 "In2.Cu" signal "IN1")
		(8 "In3.Cu" signal "GND1")
		(10 "In4.Cu" signal "IN2")
		(12 "In5.Cu" signal "GND2")
		(14 "In6.Cu" signal "IN3")
		(16 "In7.Cu" signal "GND3")
		(18 "In8.Cu" signal "VCC")
		(20 "In9.Cu" signal "VCC1")
		(22 "In10.Cu" signal "GND4")
		(24 "In11.Cu" signal "IN4")
		(26 "In12.Cu" signal "GND5")
		(28 "In13.Cu" signal "IN5")
		(30 "In14.Cu" signal "GND6")
		(32 "In15.Cu" signal "IN6")
		(34 "In16.Cu" signal "GND7")
		(2 "B.Cu" signal "BOTTOM")
		(9 "F.Adhes" user "F.Adhesive")
		(11 "B.Adhes" user "B.Adhesive")
		(13 "F.Paste" user "Package Geometry/Pastemask Top")
		(15 "B.Paste" user "Package Geometry/Pastemask Bottom")
		(5 "F.SilkS" user "Ref Des/Silkscreen Top")
		(7 "B.SilkS" user "Ref Des/Silkscreen Bottom")
		(1 "F.Mask" user "Board Geometry/Soldermask Top")
		(3 "B.Mask" user "Board Geometry/Soldermask Bottom")
		(17 "Dwgs.User" user "User.Drawings")
		(19 "Cmts.User" user "User.Comments")
		(21 "Eco1.User" user "User.Eco1")
		(23 "Eco2.User" user "User.Eco2")
		(25 "Edge.Cuts" user "Board Geometry/Outline")
		(27 "Margin" user)
		(31 "F.CrtYd" user "Package Geometry/Place Bound Top")
		(29 "B.CrtYd" user "Package Geometry/Place Bound Bottom")
		(35 "F.Fab" user "Ref Des/Assembly Top")
		(33 "B.Fab" user "Ref Des/Assembly Bottom")
	)
	(footprint ""
		(layer "B.Cu")
		(at 52.730908 -193.25971 -90)
		(property "Reference" "R1394"
			(at 0 0 90)
			(layer "B.SilkS")
			(hide yes)
			(effects
				(font
					(size 1.27 1.27)
				)
				(justify mirror)
			)
		)
		(property "Value" ""
			(at 0 0 90)
			(layer "B.Fab")
			(effects
				(font
					(size 1.27 1.27)
				)
				(justify mirror)
			)
		)
		(duplicate_pad_numbers_are_jumpers no)
		(fp_line
			(start -0.7874 0.4064)
			(end 0.7874 0.4064)
			(stroke
				(width 0.1524)
				(type default)
			)
			(layer "B.SilkS")
		)
		(fp_line
			(start 0.7874 0.4064)
			(end 0.7874 -0.4064)
			(stroke
				(width 0.1524)
				(type default)
			)
			(layer "B.SilkS")
		)
		(fp_line
			(start -0.7874 -0.4064)
			(end -0.7874 0.4064)
			(stroke
				(width 0.1524)
				(type default)
			)
			(layer "B.SilkS")
		)
		(fp_line
			(start 0.7874 -0.4064)
			(end -0.7874 -0.4064)
			(stroke
				(width 0.1524)
				(type default)
			)
			(layer "B.SilkS")
		)
		(fp_line
			(start -0.67945 0.3048)
			(end -0.120396 0.3048)
			(stroke
				(width 0.1)
				(type default)
			)
			(layer "B.Fab")
		)
		(fp_line
			(start -0.120396 0.3048)
			(end -0.120396 0.2794)
			(stroke
				(width 0.1)
				(type default)
			)
			(layer "B.Fab")
		)
		(fp_line
			(start 0.12065 0.3048)
			(end 0.67945 0.3048)
			(stroke
				(width 0.1)
				(type default)
			)
			(layer "B.Fab")
		)
		(fp_line
			(start 0.67945 0.3048)
			(end 0.67945 -0.305054)
			(stroke
				(width 0.1)
				(type default)
			)
			(layer "B.Fab")
		)
		(fp_line
			(start -0.120396 0.2794)
			(end 0.12065 0.2794)
			(stroke
				(width 0.1)
				(type default)
			)
			(layer "B.Fab")
		)
		(fp_line
			(start 0.12065 0.2794)
			(end 0.12065 0.3048)
			(stroke
				(width 0.1)
				(type default)
			)
			(layer "B.Fab")
		)
		(fp_line
			(start -0.12065 -0.2794)
			(end -0.12065 -0.3048)
			(stroke
				(width 0.1)
				(type default)
			)
			(layer "B.Fab")
		)
		(fp_line
			(start 0.12065 -0.2794)
			(end -0.12065 -0.2794)
			(stroke
				(width 0.1)
				(type default)
			)
			(layer "B.Fab")
		)
		(fp_line
			(start -0.67945 -0.3048)
			(end -0.67945 0.3048)
			(stroke
				(width 0.1)
				(type default)
			)
			(layer "B.Fab")
		)
		(fp_line
			(start -0.12065 -0.3048)
			(end -0.67945 -0.3048)
			(stroke
				(width 0.1)
				(type default)
			)
			(layer "B.Fab")
		)
		(fp_line
			(start 0.12065 -0.305054)
			(end 0.12065 -0.2794)
			(stroke
				(width 0.1)
				(type default)
			)
			(layer "B.Fab")
		)
		(fp_line
			(start 0.67945 -0.305054)
			(end 0.12065 -0.305054)
			(stroke
				(width 0.1)
				(type default)
			)
			(layer "B.Fab")
		)
		(pad "1" smd circle
			(at 0.40005 0 90)
			(size 0 0)
			(layers "B.Cu" "B.Mask" "B.Paste")
			(net "GND")
		)
		(pad "2" smd circle
			(at -0.40005 0 90)
			(size 0 0)
			(layers "B.Cu" "B.Mask" "B.Paste")
			(net "FM_S3M_CPU1_LVC1_GPIO_3")
		)
	)
	(footprint ""
		(layer "B.Cu")
		(at 178.26482 -356.41153 -90)
		(property "Reference" "PR1333"
			(at 0 0 90)
			(layer "B.SilkS")
			(hide yes)
			(effects
				(font
					(size 1.27 1.27)
				)
				(justify mirror)
			)
		)
		(property "Value" ""
			(at 0 0 90)
			(layer "B.Fab")
			(effects
				(font
					(size 1.27 1.27)
				)
				(justify mirror)
			)
		)
		(duplicate_pad_numbers_are_jumpers no)
		(fp_line
			(start -0.7874 0.4064)
			(end 0.7874 0.4064)
			(stroke
				(width 0.1524)
				(type default)
			)
			(layer "B.SilkS")
		)
		(fp_line
			(start 0.7874 0.4064)
			(end 0.7874 -0.4064)
			(stroke
				(width 0.1524)
				(type default)
			)
			(layer "B.SilkS")
		)
		(fp_line
			(start -0.7874 -0.4064)
			(end -0.7874 0.4064)
			(stroke
				(width 0.1524)
				(type default)
			)
			(layer "B.SilkS")
		)
		(fp_line
			(start 0.7874 -0.4064)
			(end -0.7874 -0.4064)
			(stroke
				(width 0.1524)
				(type default)
			)
			(layer "B.SilkS")
		)
		(fp_line
			(start -0.67945 0.3048)
			(end -0.120396 0.3048)
			(stroke
				(width 0.1)
				(type default)
			)
			(layer "B.Fab")
		)
		(fp_line
			(start -0.120396 0.3048)
			(end -0.120396 0.2794)
			(stroke
				(width 0.1)
				(type default)
			)
			(layer "B.Fab")
		)
		(fp_line
			(start 0.12065 0.3048)
			(end 0.67945 0.3048)
			(stroke
				(width 0.1)
				(type default)
			)
			(layer "B.Fab")
		)
		(fp_line
			(start 0.67945 0.3048)
			(end 0.67945 -0.305054)
			(stroke
				(width 0.1)
				(type default)
			)
			(layer "B.Fab")
		)
		(fp_line
			(start -0.120396 0.2794)
			(end 0.12065 0.2794)
			(stroke
				(width 0.1)
				(type default)
			)
			(layer "B.Fab")
		)
		(fp_line
			(start 0.12065 0.2794)
			(end 0.12065 0.3048)
			(stroke
				(width 0.1)
				(type default)
			)
			(layer "B.Fab")
		)
		(fp_line
			(start -0.12065 -0.2794)
			(end -0.12065 -0.3048)
			(stroke
				(width 0.1)
				(type default)
			)
			(layer "B.Fab")
		)
		(fp_line
			(start 0.12065 -0.2794)
			(end -0.12065 -0.2794)
			(stroke
				(width 0.1)
				(type default)
			)
			(layer "B.Fab")
		)
		(fp_line
			(start -0.67945 -0.3048)
			(end -0.67945 0.3048)
			(stroke
				(width 0.1)
				(type default)
			)
			(layer "B.Fab")
		)
		(fp_line
			(start -0.12065 -0.3048)
			(end -0.67945 -0.3048)
			(stroke
				(width 0.1)
				(type default)
			)
			(layer "B.Fab")
		)
		(fp_line
			(start 0.12065 -0.305054)
			(end 0.12065 -0.2794)
			(stroke
				(width 0.1)
				(type default)
			)
			(layer "B.Fab")
		)
		(fp_line
			(start 0.67945 -0.305054)
			(end 0.12065 -0.305054)
			(stroke
				(width 0.1)
				(type default)
			)
			(layer "B.Fab")
		)
		(pad "1" smd circle
			(at 0.40005 0 90)
			(size 0 0)
			(layers "B.Cu" "B.Mask" "B.Paste")
			(net "PVCCFA_EHV_FIVRA_CPU1_VOS3")
		)
		(pad "2" smd circle
			(at -0.40005 0 90)
			(size 0 0)
			(layers "B.Cu" "B.Mask" "B.Paste")
			(net "PVCCFA_EHV_FIVRA_CPU1")
		)
	)
	(footprint ""
		(layer "B.Cu")
		(at 118.370604 -296.05478)
		(property "Reference" "C352"
			(at 0 0 0)
			(layer "B.SilkS")
			(hide yes)
			(effects
				(font
					(size 1.27 1.27)
				)
				(justify mirror)
			)
		)
		(property "Value" ""
			(at 0 0 0)
			(layer "B.Fab")
			(effects
				(font
					(size 1.27 1.27)
				)
				(justify mirror)
			)
		)
		(duplicate_pad_numbers_are_jumpers no)
		(fp_line
			(start -1.524 -0.762)
			(end -1.524 0.762)
			(stroke
				(width 0.1524)
				(type default)
			)
			(layer "B.SilkS")
		)
		(fp_line
			(start -1.524 0.762)
			(end 1.524 0.762)
			(stroke
				(width 0.1524)
				(type default)
			)
			(layer "B.SilkS")
		)
		(fp_line
			(start 1.524 -0.762)
			(end -1.524 -0.762)
			(stroke
				(width 0.1524)
				(type default)
			)
			(layer "B.SilkS")
		)
		(fp_line
			(start 1.524 0.762)
			(end 1.524 -0.762)
			(stroke
				(width 0.1524)
				(type default)
			)
			(layer "B.SilkS")
		)
		(fp_line
			(start -1.1049 -0.724916)
			(end 1.1049 -0.724916)
			(stroke
				(width 0.1)
				(type default)
			)
			(layer "B.Fab")
		)
		(fp_line
			(start -1.1049 0.724916)
			(end -1.1049 -0.724916)
			(stroke
				(width 0.1)
				(type default)
			)
			(layer "B.Fab")
		)
		(fp_line
			(start 1.1049 -0.724916)
			(end 1.1049 0.724916)
			(stroke
				(width 0.1)
				(type default)
			)
			(layer "B.Fab")
		)
		(fp_line
			(start 1.1049 0.724916)
			(end -1.1049 0.724916)
			(stroke
				(width 0.1)
				(type default)
			)
			(layer "B.Fab")
		)
		(pad "1" smd rect
			(at 0.889 0)
			(size 1.016 1.27)
			(layers "B.Cu" "B.Mask" "B.Paste")
			(net "PVCCIN_CPU1")
		)
		(pad "2" smd rect
			(at -0.889 0)
			(size 1.016 1.27)
			(layers "B.Cu" "B.Mask" "B.Paste")
			(net "GND")
		)
	)
)
